# S9S_MB_2U (Grand Teton) — schematic parts with pin connectivity, parts 2207–2373 of 6093; source: Cadence DE-HDL packaged netlist (pstxprt.dat, pstxnet.dat, pstchip.dat)

PC1254  Q_CAP  0.1UF 25V 10% X7R  pkg 0402  page 281 : 1 = PVPP_HBM_CPU0 ; 2 = GND
PC1255  Q_CAP  22UF 4V 20% X6S  pkg C0805  page 281 : 1 = PVPP_HBM_CPU0 ; 2 = GND
PC1256  Q_CAP  22UF 4V 20% X6S  pkg C0805  page 281 : 1 = PVPP_HBM_CPU0 ; 2 = GND
PC1257  Q_CAP  22UF 4V 20% X6S  pkg C0805  page 281 : 1 = PVPP_HBM_CPU0 ; 2 = GND
PC1258  Q_CAPP  560UF 6.3V 20% OSCON  pkg THLF  page 281 : 1 = PVPP_HBM_CPU0 ; 2 = GND
PC1259  Q_CAP  22UF 16V 20% X6S  pkg C0805  page 299 : 1 = SW_P12V_PVCCIN_CPU1_FLT ; 2 = GND
PC1260  Q_CAP  22UF 16V 20% X6S  pkg C0805  page 299 : 1 = SW_P12V_PVCCIN_CPU1_FLT ; 2 = GND
PC1261  Q_CAP  22UF 16V 20% X6S  pkg C0805  page 299 : 1 = SW_P12V_PVCCIN_CPU1_FLT ; 2 = GND
PC1262  Q_CAP  1UF 16V 10% X6S  pkg C0402  page 299 : 1 = SW_P12V_PVCCIN_CPU1_FLT ; 2 = GND
PC1264  Q_CAP  0.1UF 25V 10% X7R  pkg 0402  page 299 : 1 = PVPP_HBM_CPU1_REF ; 2 = SH_PVPP_HBM_CPU1_N
PC1265  Q_CAP  0.22UF 25V 10% X7R  pkg C0402  page 299 : 1 = SW_PVPP_HBM_CPU1_BST ; 2 = SW_PVPP_HBM_CPU1_SW
PC1266  Q_CAP  680PF 50V 10% X7R  pkg 0402  page 299 : 1 = PVPP_HBM_CPU1_FB ; 2 = SH_PVPP_HBM_CPU1_P
PC1267  Q_CAP  0.1UF 25V 10% X7R  pkg 0402  page 299 : 1 = PVPP_HBM_CPU1 ; 2 = GND
PC1268  Q_CAP  22UF 4V 20% X6S  pkg C0805  page 299 : 1 = PVPP_HBM_CPU1 ; 2 = GND
PC1269  Q_CAP  22UF 4V 20% X6S  pkg C0805  page 299 : 1 = PVPP_HBM_CPU1 ; 2 = GND
PC1270  Q_CAP  22UF 4V 20% X6S  pkg C0805  page 299 : 1 = PVPP_HBM_CPU1 ; 2 = GND
PC1271  Q_CAP  470PF 50V 10% X7R  pkg 0402  page 274 : 1 = PVCCFA_EHV_CPU0_BTSEN ; 2 = GND
PC1272  Q_CAP  22UF 16V 20% X6S  pkg C0805  page 282 : 1 = SW_P12V_PVCCINFAON_CPU0_FLT ; 2 = GND
PC1273  Q_CAP  22UF 16V 20% X6S  pkg C0805  page 282 : 1 = SW_P12V_PVCCINFAON_CPU0_FLT ; 2 = GND
PC1274  Q_CAP  1UF 16V 10% X6S  pkg C0402  page 282 : 1 = SW_P12V_PVCCINFAON_CPU0_FLT ; 2 = GND
PC1275  Q_CAP  0.22UF 25V 10% X7R  pkg C0402  page 282 : 1 = SW_PVNN_MAIN_CPU0_BST_R ; 2 = SW_PVNN_MAIN_CPU0_SW
PC1276  Q_CAP  100NF 50V 10% X7R  pkg C0402  page 282 : 1 = PVNN_MAIN_CPU0 ; 2 = GND
PC1277  Q_CAP  22UF 4V 20% X6S  pkg C0805  page 282 : 1 = PVNN_MAIN_CPU0 ; 2 = GND
PC1278  Q_CAP  22UF 4V 20% X6S  pkg C0805  page 282 : 1 = PVNN_MAIN_CPU0 ; 2 = GND
PC1279  Q_CAP  22UF 4V 20% X6S  pkg C0805  page 282 : 1 = PVNN_MAIN_CPU0 ; 2 = GND
PC1280  Q_CAP  22UF 16V 20% X6S  pkg C0805  page 300 : 1 = SW_P12V_PVCCINFAON_CPU1_FLT ; 2 = GND
PC1281  Q_CAP  22UF 16V 20% X6S  pkg C0805  page 300 : 1 = SW_P12V_PVCCINFAON_CPU1_FLT ; 2 = GND
PC1282  Q_CAP  1UF 16V 10% X6S  pkg C0402  page 300 : 1 = SW_P12V_PVCCINFAON_CPU1_FLT ; 2 = GND
PC1283  Q_CAP  0.22UF 25V 10% X7R  pkg C0402  page 300 : 1 = SW_PVNN_MAIN_CPU1_BST_R ; 2 = SW_PVNN_MAIN_CPU1_SW
PC1284  Q_CAP  100NF 50V 10% X7R  pkg C0402  page 300 : 1 = PVNN_MAIN_CPU1 ; 2 = GND
PC1285  Q_CAP  22UF 4V 20% X6S  pkg C0805  page 300 : 1 = PVNN_MAIN_CPU1 ; 2 = GND
PC1286  Q_CAP  22UF 4V 20% X6S  pkg C0805  page 300 : 1 = PVNN_MAIN_CPU1 ; 2 = GND
PC1287  Q_CAP  22UF 4V 20% X6S  pkg C0805  page 300 : 1 = PVNN_MAIN_CPU1 ; 2 = GND
PC1289  Q_CAP  1UF 16V 10% X6S  pkg C0402  page 296 : 1 = PVCCD_HV_CPU1_VREF ; 2 = GND
PC1292  Q_CAP  470PF 50V 10% X7R  pkg 0402  page 292 : 1 = PVCCFA_EHV_CPU1_BTSEN ; 2 = GND
PC1320  Q_CAP  2.2UF 16V 20% X7R  pkg C0603  page 163 : 1 = P12V_OCP_AVIN_PD_2 ; 2 = GND
PC1321  Q_CAP  0.068UF 16V 10% EMPTY  pkg 0402  page 163 : 1 = P3V3_OCP_DVDT_2 ; 2 = GND
PC1322  Q_CAP  100PF 50V 5% EMPTY  pkg 0402  page 163 : 1 = P3V3_OCP_GATE_PU207_2 ; 2 = GND
PC1338  Q_CAP  0.1UF 25V 10% X7R  pkg 0402  page 285 : 1 = GND ; 2 = PVCCIN_CPU1_VREF
PC1339  Q_CAP  0.1UF 25V 10% X7R  pkg 0402  page 285 : 1 = GND ; 2 = PVCCIN_CPU1_VREF
PC1340  Q_CAP  0.1UF 25V 10% X7R  pkg 0402  page 268 : 1 = GND ; 2 = PVCCIN_CPU0_VREF
PC1341  Q_CAP  0.1UF 25V 10% X7R  pkg 0402  page 268 : 1 = GND ; 2 = PVCCIN_CPU0_VREF
PC1342  Q_CAP  0.1UF 25V 10% X7R  pkg 0402  page 269 : 1 = GND ; 2 = PVCCIN_CPU0_VREF
PC1343  Q_CAP  0.1UF 25V 10% X7R  pkg 0402  page 269 : 1 = GND ; 2 = PVCCIN_CPU0_VREF
PC1344  Q_CAP  0.1UF 25V 10% X7R  pkg 0402  page 270 : 1 = GND ; 2 = PVCCIN_CPU0_VREF
PC1345  Q_CAP  0.1UF 25V 10% X7R  pkg 0402  page 270 : 1 = GND ; 2 = PVCCIN_CPU0_VREF
PC1346  Q_CAP  0.1UF 25V 10% X7R  pkg 0402  page 275 : 1 = GND ; 2 = PVCCINFAON_CPU0_VREF
PC1347  Q_CAP  0.1UF 25V 10% X7R  pkg 0402  page 275 : 1 = GND ; 2 = PVCCINFAON_CPU0_VREF
PC1348  Q_CAP  0.1UF 25V 10% X7R  pkg 0402  page 276 : 1 = GND ; 2 = PVCCINFAON_CPU0_VREF
PC1349  Q_CAP  0.1UF 25V 10% X7R  pkg 0402  page 271 : 1 = GND ; 2 = PVCCIN_CPU0_VREF
PC1350  Q_CAP  0.1UF 25V 10% X7R  pkg 0402  page 271 : 1 = GND ; 2 = PVCCIN_CPU0_VREF
PC1351  Q_CAP  0.1UF 25V 10% X7R  pkg 0402  page 272 : 1 = GND ; 2 = PVCCIN_CPU0_VREF
PC1352  Q_CAP  0.1UF 25V 10% X7R  pkg 0402  page 272 : 1 = GND ; 2 = PVCCIN_CPU0_VREF
PC1354  Q_CAP  0.1UF 25V 10% X7R  pkg 0402  page 279 : 1 = GND ; 2 = PVCCD_HV_CPU0_VREF
PC1355  Q_CAP  0.1UF 25V 10% X7R  pkg 0402  page 267 : 1 = GND ; 2 = PVCCIN_CPU0_VREF
PC1356  Q_CAP  0.1UF 25V 10% X7R  pkg 0402  page 267 : 1 = GND ; 2 = PVCCIN_CPU0_VREF
PC1358  Q_CAP  0.1UF 25V 10% X7R  pkg 0402  page 286 : 1 = GND ; 2 = PVCCIN_CPU1_VREF
PC1359  Q_CAP  0.1UF 25V 10% X7R  pkg 0402  page 286 : 1 = GND ; 2 = PVCCIN_CPU1_VREF
PC1360  Q_CAP  0.1UF 25V 10% X7R  pkg 0402  page 287 : 1 = GND ; 2 = PVCCIN_CPU1_VREF
PC1361  Q_CAP  0.1UF 25V 10% X7R  pkg 0402  page 287 : 1 = GND ; 2 = PVCCIN_CPU1_VREF
PC1362  Q_CAP  0.1UF 25V 10% X7R  pkg 0402  page 288 : 1 = GND ; 2 = PVCCIN_CPU1_VREF
PC1363  Q_CAP  0.1UF 25V 10% X7R  pkg 0402  page 288 : 1 = GND ; 2 = PVCCIN_CPU1_VREF
PC1364  Q_CAP  0.1UF 25V 10% X7R  pkg 0402  page 293 : 1 = GND ; 2 = PVCCINFAON_CPU1_VREF
PC1365  Q_CAP  0.1UF 25V 10% X7R  pkg 0402  page 293 : 1 = GND ; 2 = PVCCINFAON_CPU1_VREF
PC1366  Q_CAP  0.1UF 25V 10% X7R  pkg 0402  page 294 : 1 = GND ; 2 = PVCCINFAON_CPU1_VREF
PC1367  Q_CAP  0.1UF 25V 10% X7R  pkg 0402  page 289 : 1 = GND ; 2 = PVCCIN_CPU1_VREF
PC1368  Q_CAP  0.1UF 25V 10% X7R  pkg 0402  page 289 : 1 = GND ; 2 = PVCCIN_CPU1_VREF
PC1369  Q_CAP  0.1UF 25V 10% X7R  pkg 0402  page 290 : 1 = GND ; 2 = PVCCIN_CPU1_VREF
PC1370  Q_CAP  0.1UF 25V 10% X7R  pkg 0402  page 290 : 1 = GND ; 2 = PVCCIN_CPU1_VREF
PC1371  Q_CAP  0.1UF 25V 10% X7R  pkg 0402  page 297 : 1 = GND ; 2 = PVCCD_HV_CPU1_VREF
PC1372  Q_CAP  1UF 16V 10% X6S  pkg C0402  page 274 : 1 = PVCCINFAON_CPU0_VREF ; 2 = GND
PC1420  Q_CAP  0.01UF 25V 10% X7R  pkg 0402  page 282 : 1 = PVNN_MAIN_CPU0_FB_RC ; 2 = GND
PC1421  Q_CAP  0.01UF 25V 10% X7R  pkg 0402  page 281 : 1 = SH_PVPP_HBM_CPU0_P ; 2 = SH_PVPP_HBM_CPU0_N
PC1525  Q_CAP  1UF 25V 10% X6S  pkg C0402  page 302 : 1 = HSC_VDD_R_1 ; 2 = AGND_HSC
PC1573  Q_CAPP  330UF 2V 35% SPCAP  pkg SMLF  page 275 : 1 = PVCCINFAON_CPU0 ; 2 = GND
PC1574  Q_CAPP  560UF 2.5V 20% OSCON  pkg THLF  page 275 : 1 = PVCCINFAON_CPU0 ; 2 = GND
PC1575  Q_CAPP  330UF 2V 35% SPCAP  pkg SMLF  page 275 : 1 = PVCCINFAON_CPU0 ; 2 = GND
PC1576  Q_CAPP  560UF 2.5V 20% OSCON  pkg THLF  page 275 : 1 = PVCCINFAON_CPU0 ; 2 = GND
PC1579  Q_CAPP  560UF 2.5V 20% OSCON  pkg THLF  page 275 : 1 = PVCCINFAON_CPU0 ; 2 = GND
PC1588  Q_CAPP  330UF 2V 35% SPCAP  pkg SMLF  page 293 : 1 = PVCCINFAON_CPU1 ; 2 = GND
PC1593  Q_CAPP  560UF 2.5V 20% OSCON  pkg THLF  page 293 : 1 = PVCCINFAON_CPU1 ; 2 = GND
PC1594  Q_CAPP  330UF 2V 35% SPCAP  pkg SMLF  page 293 : 1 = PVCCINFAON_CPU1 ; 2 = GND
PC1595  Q_CAPP  560UF 2.5V 20% OSCON  pkg THLF  page 293 : 1 = PVCCINFAON_CPU1 ; 2 = GND
PC1596  Q_CAPP  560UF 2.5V 20% OSCON  pkg THLF  page 293 : 1 = PVCCINFAON_CPU1 ; 2 = GND
PC1599  Q_CAP  22UF 10V 20% X6S  pkg C0805  page 259 : 1 = P3V3_AUX ; 2 = GND
PC1600  Q_CAP  22UF 10V 20% X6S  pkg C0805  page 259 : 1 = P3V3_AUX ; 2 = GND
PC1642  Q_CAP  1UF 25V 10% X6S  pkg C0402  page 263 : 1 = P1V8_PCH_AUX_VCC ; 2 = GND
PC1644  Q_CAPP  560UF 2.5V 20% OSCON  pkg THLF  page 279 : 1 = PVCCD_HV_CPU0 ; 2 = GND
PC1645  Q_CAPP  560UF 2.5V 20% OSCON  pkg THLF  page 279 : 1 = PVCCD_HV_CPU0 ; 2 = GND
PC1648  Q_CAP  100NF 50V 10% X7R  pkg C0402  page 258 : 1 = P12V_AUX ; 2 = GND
PC1649  Q_CAP  100NF 50V 10% X7R  pkg C0402  page 259 : 1 = P12V_AUX ; 2 = GND
PC1650  Q_CAP  100NF 50V 10% X7R  pkg C0402  page 262 : 1 = P12V_AUX ; 2 = GND
PC1651  Q_CAP  100NF 50V 10% X7R  pkg C0402  page 263 : 1 = P12V_AUX ; 2 = GND
PC1652  Q_CAP  100NF 50V 10% X7R  pkg C0402  page 267 : 1 = P12V_AUX ; 2 = GND
PC1653  Q_CAP  100NF 50V 10% X7R  pkg C0402  page 271 : 1 = P12V_AUX ; 2 = GND
PC1654  Q_CAP  100NF 50V 10% X7R  pkg C0402  page 272 : 1 = P12V_AUX ; 2 = GND
PC1655  Q_CAP  100NF 50V 10% X7R  pkg C0402  page 275 : 1 = P12V_AUX ; 2 = GND
PC1656  Q_CAP  100NF 50V 10% X7R  pkg C0402  page 285 : 1 = P12V_AUX ; 2 = GND
PC1657  Q_CAP  100NF 50V 10% X7R  pkg C0402  page 289 : 1 = P12V_AUX ; 2 = GND
PC1658  Q_CAP  100NF 50V 10% X7R  pkg C0402  page 290 : 1 = P12V_AUX ; 2 = GND
PC1659  Q_CAP  100NF 50V 10% X7R  pkg C0402  page 293 : 1 = P12V_AUX ; 2 = GND
PC1669  Q_CAP  22UF 16V 20% X6S  pkg C0805  page 271 : 1 = SW_P12V_PVCCFA_EHV_FIVRA_CPU0_L ; 2 = GND
PC1670  Q_CAP  22UF 16V 20% X6S  pkg C0805  page 271 : 1 = SW_P12V_PVCCFA_EHV_FIVRA_CPU0_L ; 2 = GND
PC1671  Q_CAP  22UF 16V 20% X6S  pkg C0805  page 271 : 1 = SW_P12V_PVCCFA_EHV_FIVRA_CPU0_L ; 2 = GND
PC1672  Q_CAP  22UF 16V 20% X6S  pkg C0805  page 271 : 1 = SW_P12V_PVCCFA_EHV_FIVRA_CPU0_L ; 2 = GND
PC1673  Q_CAP  22UF 16V 20% X6S  pkg C0805  page 272 : 1 = SW_P12V_PVCCFA_EHV_FIVRA_CPU0_R ; 2 = GND
PC1674  Q_CAP  22UF 16V 20% X6S  pkg C0805  page 272 : 1 = SW_P12V_PVCCFA_EHV_FIVRA_CPU0_R ; 2 = GND
PC1675  Q_CAP  22UF 16V 20% X6S  pkg C0805  page 272 : 1 = SW_P12V_PVCCFA_EHV_FIVRA_CPU0_R ; 2 = GND
PC1676  Q_CAP  22UF 16V 20% X6S  pkg C0805  page 272 : 1 = SW_P12V_PVCCFA_EHV_FIVRA_CPU0_R ; 2 = GND
PC1677  Q_CAP  22UF 16V 20% X6S  pkg C0805  page 289 : 1 = SW_P12V_PVCCFA_EHV_FIVRA_CPU1_L ; 2 = GND
PC1678  Q_CAP  22UF 16V 20% X6S  pkg C0805  page 289 : 1 = SW_P12V_PVCCFA_EHV_FIVRA_CPU1_L ; 2 = GND
PC1679  Q_CAP  22UF 16V 20% X6S  pkg C0805  page 289 : 1 = SW_P12V_PVCCFA_EHV_FIVRA_CPU1_L ; 2 = GND
PC1680  Q_CAP  22UF 16V 20% X6S  pkg C0805  page 289 : 1 = SW_P12V_PVCCFA_EHV_FIVRA_CPU1_L ; 2 = GND
PC1681  Q_CAP  22UF 16V 20% X6S  pkg C0805  page 290 : 1 = SW_P12V_PVCCFA_EHV_FIVRA_CPU1_R ; 2 = GND
PC1682  Q_CAP  22UF 16V 20% X6S  pkg C0805  page 290 : 1 = SW_P12V_PVCCFA_EHV_FIVRA_CPU1_R ; 2 = GND
PC1683  Q_CAP  22UF 16V 20% X6S  pkg C0805  page 290 : 1 = SW_P12V_PVCCFA_EHV_FIVRA_CPU1_R ; 2 = GND
PC1684  Q_CAP  22UF 16V 20% X6S  pkg C0805  page 290 : 1 = SW_P12V_PVCCFA_EHV_FIVRA_CPU1_R ; 2 = GND
PC1750  Q_CAP  33NF 25V 10% EMPTY  pkg C0402  page 304 : 1 = P12V_AUX ; 2 = P12V_HSC_GATE2
PC1751  Q_CAP  1NF 50V 10% EMPTY  pkg 0402  page 304 : 1 = P12V_HSC_GATE_RC ; 2 = P12V_HSC_GATE2
PC1771  Q_CAPP  560UF 6.3V 20% OSCON  pkg THLF  page 299 : 1 = PVPP_HBM_CPU1 ; 2 = GND
PC1789  Q_CAP  0.1UF 25V 10% EMPTY  pkg 0402  page 305 : 1 = P12V_AUX ; 2 = GND
PC1845  Q_CAPP  220UF 6.3V 20% ALUM  pkg SMLF  page 258 : 1 = P5V_AUX ; 2 = GND
PC1846  Q_CAP  1UF 16V 10% X6S  pkg C0402  page 258 : 1 = SW_P5V_AUX_FLT ; 2 = GND
PC1847  Q_CAP  0.22UF 25V 10% X7R  pkg C0402  page 258 : 1 = SW_P5V_AUX_BST ; 2 = SW_P5V_AUX_SW
PC1848  Q_CAP  1UF 25V 10% X6S  pkg C0402  page 258 : 1 = P5V_AUX_VCC ; 2 = GND
PC1849  Q_CAP  22UF 16V 20% X6S  pkg C0805  page 258 : 1 = SW_P5V_AUX_FLT ; 2 = GND
PC1850  Q_CAP  22UF 16V 20% X6S  pkg C0805  page 258 : 1 = SW_P5V_AUX_FLT ; 2 = GND
PC1852  Q_CAP  0.1UF 25V 10% X7R  pkg 0402  page 258 : 1 = P5V_AUX ; 2 = GND
PC1853  Q_CAP  0.1UF 25V 10% X7R  pkg 0402  page 258 : 1 = P5V_AUX_REF ; 2 = GND
PC1855  Q_CAP  22UF 10V 20% X6S  pkg C0805  page 258 : 1 = P5V_AUX ; 2 = GND
PC1856  Q_CAP  22UF 10V 20% X6S  pkg C0805  page 258 : 1 = P5V_AUX ; 2 = GND
PC1866  Q_CAPP  560UF 6.3V 20% OSCON  pkg THLF  page 259 : 1 = P3V3_AUX ; 2 = GND
PC1867  Q_CAPP  560UF 6.3V 20% OSCON  pkg THLF  page 259 : 1 = P3V3_AUX ; 2 = GND
PC1868  Q_CAP  22UF 10V 20% X6S  pkg C0805  page 259 : 1 = P3V3_AUX ; 2 = GND
PC1869  Q_CAP  0.1UF 25V 10% X7R  pkg 0402  page 259 : 1 = P3V3_AUX ; 2 = GND
PC1877  Q_CAP  47PF 50V 5% NPO  pkg 0402  page 258 : 1 = P5V_AUX_FB ; 2 = P5V_AUX
PC1898  Q_CAP  22UF 16V 20% X6S  pkg C0805  page 258 : 1 = SW_P5V_AUX_FLT ; 2 = GND
PC1900  Q_CAPP  330UF 2.5V +10/-35% SPCAP  pkg SMLF  page 276 : 1 = PVCCFA_EHV_CPU0 ; 2 = GND
PC1910  Q_CAPP  330UF 2V 35% SPCAP  pkg SMLF  page 279 : 1 = PVCCD_HV_CPU0 ; 2 = GND
PC1920  Q_CAPP  330UF 2.5V +10/-35% EMPTY  pkg SMLF  page 267 : 1 = PVCCIN_CPU0 ; 2 = GND
PC1930  Q_CAPP  330UF 2.5V +10/-35% SPCAP  pkg SMLF  page 294 : 1 = PVCCFA_EHV_CPU1 ; 2 = GND
PC1940  Q_CAPP  330UF 2V 35% SPCAP  pkg SMLF  page 297 : 1 = PVCCD_HV_CPU1 ; 2 = GND
PC1990  Q_CAPP  330UF 2.5V +10/-35% EMPTY  pkg SMLF  page 285 : 1 = PVCCIN_CPU1 ; 2 = GND
PC2000  Q_CAP  0.022UF 16V 10% X7R  pkg 0402  page 262 : 1 = P1V05_PCH_AUX_REF ; 2 = GND
PC2001  Q_CAP  0.022UF 16V 10% X7R  pkg 0402  page 281 : 1 = PVPP_HBM_CPU0_REF ; 2 = GND
PC2002  Q_CAP  0.022UF 16V 10% X7R  pkg 0402  page 299 : 1 = PVPP_HBM_CPU1_REF ; 2 = GND
PC2079  Q_CAP  1UF 25V 10% X6S  pkg C0402  page 156 : 1 = P12V_AUX ; 2 = GND
PC2080  Q_CAP  22UF 16V 20% X6S  pkg C0805  page 156 : 1 = P12V_OCP_SFF ; 2 = GND
PC2081  Q_CAP  10UF 16V 10% X6S  pkg C0805  page 156 : 1 = P3V3_OCP_SFF_R ; 2 = GND
PC2082  Q_CAP  10UF 16V 10% X6S  pkg C0805  page 156 : 1 = P12V_OCP_SFF ; 2 = GND
PC2085  Q_CAP  1UF 25V 10% EMPTY  pkg C0402  page 156 : 1 = P12V_OCP_VCC_1 ; 2 = GND
PC2086  Q_CAP  1UF 25V 10% X6S  pkg C0402  page 156 : 1 = P3V3_OCP_VCC_1 ; 2 = GND
PC2087  Q_CAP  1UF 25V 10% EMPTY  pkg C0402  page 156 : 1 = GND ; 2 = P12V_OCP_REG_1
PC2088  Q_CAP  0.01UF 50V 10% EMPTY  pkg C0402  page 156 : 1 = P12V_OCP_SFF ; 2 = P12V_OCP_GATE_1
PC2089  Q_CAP  6800PF 50V 10% X7R  pkg C0402  page 156 : 1 = P3V3_OCP_GATE_PU202_1 ; 2 = GND
PC2091  Q_CAP  0.1UF 25V 10% X7R  pkg 0402  page 156 : 1 = P3V3_OCP_SFF_R ; 2 = GND
PC2092  Q_CAP  0.1UF 25V 10% X7R  pkg 0402  page 156 : 1 = P12V_OCP_SFF ; 2 = GND
PC2093  Q_CAP  1UF 25V 10% X6S  pkg C0402  page 156 : 1 = GND ; 2 = P3V3_OCP_REG_1
PC2098  Q_CAP  1UF 25V 10% EMPTY  pkg C0402  page 162 : 1 = P12V_OCP_VCC_2 ; 2 = GND
PC2103  Q_CAP  1UF 25V 10% X6S  pkg C0402  page 301 : 1 = HSC_VDD18 ; 2 = AGND_HSC
PC2137  Q_CAP  0.1UF 25V 10% X7R  pkg 0402  page 162 : 1 = P3V3_OCP_V3_2_R ; 2 = GND
PC2139  Q_CAP  1UF 25V 10% X6S  pkg C0402  page 162 : 1 = P12V_AUX ; 2 = GND
PC2140  Q_CAP  1UF 25V 10% X6S  pkg C0402  page 162 : 1 = P3V3_AUX ; 2 = GND
PC2141  Q_CAP  22UF 16V 20% X6S  pkg C0805  page 162 : 1 = P12V_OCP_V3_2 ; 2 = GND
PC2142  Q_CAP  10UF 16V 10% X6S  pkg C0805  page 162 : 1 = P3V3_OCP_V3_2_R ; 2 = GND
PC2143  Q_CAP  10UF 16V 10% X6S  pkg C0805  page 162 : 1 = P12V_OCP_V3_2 ; 2 = GND
PC2144  Q_CAP  0.01UF 50V 10% EMPTY  pkg C0402  page 156 : 1 = P3V3_OCP_SFF_R ; 2 = P3V3_OCP_GATE_PU202_1
